# S9S_MB_2U (Grand Teton) — schematic netlist excerpt (pin names and nets, part order shuffled) for the footprints in the layout excerpt that follows; sources: Cadence DE-HDL packaged netlist, KiCad conversion of 03242023_DA0F0TMBIJ0_F0T_Motherboard_J_brd_V01_OCP.brd

C2447  Q_CAP  1000PF 50V 5% EMPTY  pkg 0402  page 284 : A = PWRGD_PVCCFA_EHV_FIVRA_CPU1_R ; B = GND
R4614  Q_RES  33.2 1% CHIP  pkg 0402LF  page 158 : A = HP_OCP_V3_1_RST ; B = HP_OCP_V3_1_RST_R

(kicad_pcb
	(version 20260206)
	(generator "pcbnew")
	(generator_version "10.0")
	(general
		(thickness 1.6)
		(legacy_teardrops no)
	)
	(paper "A4")
	(title_block
		(title "03242023_DA0F0TMBIJ0_F0T_Motherboard_J_brd_V01_OCP.brd")
		(comment 1 "Grand Teton / footprints 2848-2849 of 6105")
	)
	(layers
		(0 "F.Cu" signal "TOP")
		(4 "In1.Cu" signal "GND")
		(6 "In2.Cu" signal "IN1")
		(8 "In3.Cu" signal "GND1")
		(10 "In4.Cu" signal "IN2")
		(12 "In5.Cu" signal "GND2")
		(14 "In6.Cu" signal "IN3")
		(16 "In7.Cu" signal "GND3")
		(18 "In8.Cu" signal "VCC")
		(20 "In9.Cu" signal "VCC1")
		(22 "In10.Cu" signal "GND4")
		(24 "In11.Cu" signal "IN4")
		(26 "In12.Cu" signal "GND5")
		(28 "In13.Cu" signal "IN5")
		(30 "In14.Cu" signal "GND6")
		(32 "In15.Cu" signal "IN6")
		(34 "In16.Cu" signal "GND7")
		(2 "B.Cu" signal "BOTTOM")
		(9 "F.Adhes" user "F.Adhesive")
		(11 "B.Adhes" user "B.Adhesive")
		(13 "F.Paste" user "Package Geometry/Pastemask Top")
		(15 "B.Paste" user "Package Geometry/Pastemask Bottom")
		(5 "F.SilkS" user "Ref Des/Silkscreen Top")
		(7 "B.SilkS" user "Ref Des/Silkscreen Bottom")
		(1 "F.Mask" user "Board Geometry/Soldermask Top")
		(3 "B.Mask" user "Board Geometry/Soldermask Bottom")
		(17 "Dwgs.User" user "User.Drawings")
		(19 "Cmts.User" user "User.Comments")
		(21 "Eco1.User" user "User.Eco1")
		(23 "Eco2.User" user "User.Eco2")
		(25 "Edge.Cuts" user "Board Geometry/Outline")
		(27 "Margin" user)
		(31 "F.CrtYd" user "Package Geometry/Place Bound Top")
		(29 "B.CrtYd" user "Package Geometry/Place Bound Bottom")
		(35 "F.Fab" user "Ref Des/Assembly Top")
		(33 "B.Fab" user "Ref Des/Assembly Bottom")
	)
	(footprint ""
		(layer "F.Cu")
		(at 389.636 -31.841948 180)
		(property "Reference" "R4614"
			(at 0 0 180)
			(layer "F.SilkS")
			(hide yes)
			(effects
				(font
					(size 1.27 1.27)
				)
			)
		)
		(property "Value" ""
			(at 0 0 180)
			(layer "F.Fab")
			(effects
				(font
					(size 1.27 1.27)
				)
			)
		)
		(duplicate_pad_numbers_are_jumpers no)
		(fp_line
			(start 0.7874 0.4064)
			(end -0.7874 0.4064)
			(stroke
				(width 0.1524)
				(type default)
			)
			(layer "F.SilkS")
		)
		(fp_line
			(start 0.7874 -0.4064)
			(end 0.7874 0.4064)
			(stroke
				(width 0.1524)
				(type default)
			)
			(layer "F.SilkS")
		)
		(fp_line
			(start -0.7874 0.4064)
			(end -0.7874 -0.4064)
			(stroke
				(width 0.1524)
				(type default)
			)
			(layer "F.SilkS")
		)
		(fp_line
			(start -0.7874 -0.4064)
			(end 0.7874 -0.4064)
			(stroke
				(width 0.1524)
				(type default)
			)
			(layer "F.SilkS")
		)
		(fp_line
			(start 0.67945 0.3048)
			(end 0.120396 0.3048)
			(stroke
				(width 0.1)
				(type default)
			)
			(layer "F.Fab")
		)
		(fp_line
			(start 0.67945 -0.3048)
			(end 0.67945 0.3048)
			(stroke
				(width 0.1)
				(type default)
			)
			(layer "F.Fab")
		)
		(fp_line
			(start 0.12065 -0.2794)
			(end 0.12065 -0.3048)
			(stroke
				(width 0.1)
				(type default)
			)
			(layer "F.Fab")
		)
		(fp_line
			(start 0.12065 -0.3048)
			(end 0.67945 -0.3048)
			(stroke
				(width 0.1)
				(type default)
			)
			(layer "F.Fab")
		)
		(fp_line
			(start 0.120396 0.3048)
			(end 0.120396 0.2794)
			(stroke
				(width 0.1)
				(type default)
			)
			(layer "F.Fab")
		)
		(fp_line
			(start 0.120396 0.2794)
			(end -0.12065 0.2794)
			(stroke
				(width 0.1)
				(type default)
			)
			(layer "F.Fab")
		)
		(fp_line
			(start -0.12065 0.3048)
			(end -0.67945 0.3048)
			(stroke
				(width 0.1)
				(type default)
			)
			(layer "F.Fab")
		)
		(fp_line
			(start -0.12065 0.2794)
			(end -0.12065 0.3048)
			(stroke
				(width 0.1)
				(type default)
			)
			(layer "F.Fab")
		)
		(fp_line
			(start -0.12065 -0.2794)
			(end 0.12065 -0.2794)
			(stroke
				(width 0.1)
				(type default)
			)
			(layer "F.Fab")
		)
		(fp_line
			(start -0.12065 -0.305054)
			(end -0.12065 -0.2794)
			(stroke
				(width 0.1)
				(type default)
			)
			(layer "F.Fab")
		)
		(fp_line
			(start -0.67945 0.3048)
			(end -0.67945 -0.305054)
			(stroke
				(width 0.1)
				(type default)
			)
			(layer "F.Fab")
		)
		(fp_line
			(start -0.67945 -0.305054)
			(end -0.12065 -0.305054)
			(stroke
				(width 0.1)
				(type default)
			)
			(layer "F.Fab")
		)
		(pad "1" smd circle
			(at -0.40005 0 180)
			(size 0 0)
			(layers "F.Cu" "F.Mask" "F.Paste")
			(net "HP_OCP_V3_1_RST")
		)
		(pad "2" smd circle
			(at 0.40005 0 180)
			(size 0 0)
			(layers "F.Cu" "F.Mask" "F.Paste")
			(net "HP_OCP_V3_1_RST_R")
		)
	)
	(footprint ""
		(layer "F.Cu")
		(at 102.844346 -358.452674 180)
		(property "Reference" "C2447"
			(at 0 0 180)
			(layer "F.SilkS")
			(hide yes)
			(effects
				(font
					(size 1.27 1.27)
				)
			)
		)
		(property "Value" ""
			(at 0 0 180)
			(layer "F.Fab")
			(effects
				(font
					(size 1.27 1.27)
				)
			)
		)
		(duplicate_pad_numbers_are_jumpers no)
		(fp_line
			(start 0.7874 0.4064)
			(end -0.7874 0.4064)
			(stroke
				(width 0.1524)
				(type default)
			)
			(layer "F.SilkS")
		)
		(fp_line
			(start 0.7874 -0.4064)
			(end 0.7874 0.4064)
			(stroke
				(width 0.1524)
				(type default)
			)
			(layer "F.SilkS")
		)
		(fp_line
			(start -0.7874 0.4064)
			(end -0.7874 -0.4064)
			(stroke
				(width 0.1524)
				(type default)
			)
			(layer "F.SilkS")
		)
		(fp_line
			(start -0.7874 -0.4064)
			(end 0.7874 -0.4064)
			(stroke
				(width 0.1524)
				(type default)
			)
			(layer "F.SilkS")
		)
		(fp_line
			(start 0.67945 0.3048)
			(end 0.120396 0.3048)
			(stroke
				(width 0.1)
				(type default)
			)
			(layer "F.Fab")
		)
		(fp_line
			(start 0.67945 -0.3048)
			(end 0.67945 0.3048)
			(stroke
				(width 0.1)
				(type default)
			)
			(layer "F.Fab")
		)
		(fp_line
			(start 0.12065 -0.2794)
			(end 0.12065 -0.3048)
			(stroke
				(width 0.1)
				(type default)
			)
			(layer "F.Fab")
		)
		(fp_line
			(start 0.12065 -0.3048)
			(end 0.67945 -0.3048)
			(stroke
				(width 0.1)
				(type default)
			)
			(layer "F.Fab")
		)
		(fp_line
			(start 0.120396 0.3048)
			(end 0.120396 0.2794)
			(stroke
				(width 0.1)
				(type default)
			)
			(layer "F.Fab")
		)
		(fp_line
			(start 0.120396 0.2794)
			(end -0.12065 0.2794)
			(stroke
				(width 0.1)
				(type default)
			)
			(layer "F.Fab")
		)
		(fp_line
			(start -0.12065 0.3048)
			(end -0.67945 0.3048)
			(stroke
				(width 0.1)
				(type default)
			)
			(layer "F.Fab")
		)
		(fp_line
			(start -0.12065 0.2794)
			(end -0.12065 0.3048)
			(stroke
				(width 0.1)
				(type default)
			)
			(layer "F.Fab")
		)
		(fp_line
			(start -0.12065 -0.2794)
			(end 0.12065 -0.2794)
			(stroke
				(width 0.1)
				(type default)
			)
			(layer "F.Fab")
		)
		(fp_line
			(start -0.12065 -0.305054)
			(end -0.12065 -0.2794)
			(stroke
				(width 0.1)
				(type default)
			)
			(layer "F.Fab")
		)
		(fp_line
			(start -0.67945 0.3048)
			(end -0.67945 -0.305054)
			(stroke
				(width 0.1)
				(type default)
			)
			(layer "F.Fab")
		)
		(fp_line
			(start -0.67945 -0.305054)
			(end -0.12065 -0.305054)
			(stroke
				(width 0.1)
				(type default)
			)
			(layer "F.Fab")
		)
		(pad "1" smd circle
			(at -0.40005 0 180)
			(size 0 0)
			(layers "F.Cu" "F.Mask" "F.Paste")
			(net "PWRGD_PVCCFA_EHV_FIVRA_CPU1_R")
		)
		(pad "2" smd circle
			(at 0.40005 0 180)
			(size 0 0)
			(layers "F.Cu" "F.Mask" "F.Paste")
			(net "GND")
		)
	)
)
